(kicad_pcb
	(version 20260206)
	(generator "pcbnew")
	(generator_version "10.0")
	(general
		(thickness 1.6)
		(legacy_teardrops no)
	)
	(paper "A4")
	(title_block
		(title "Bryce Canyon_SCC_16316-1_OCP.brd")
		(comment 1 "Bryce Canyon / footprints 334-341 of 1561")
	)
	(layers
		(0 "F.Cu" signal "TOP")
		(4 "In1.Cu" signal "L2GND")
		(6 "In2.Cu" signal "L3")
		(8 "In3.Cu" signal "L4VCC")
		(10 "In4.Cu" signal "L5VCC")
		(12 "In5.Cu" signal "L6")
		(14 "In6.Cu" signal "L7GND")
		(2 "B.Cu" signal "BOTTOM")
		(9 "F.Adhes" user "F.Adhesive")
		(11 "B.Adhes" user "B.Adhesive")
		(13 "F.Paste" user "Package Geometry/Pastemask Top")
		(15 "B.Paste" user "Package Geometry/Pastemask Bottom")
		(5 "F.SilkS" user "Ref Des/Silkscreen Top")
		(7 "B.SilkS" user "Ref Des/Silkscreen Bottom")
		(1 "F.Mask" user "Board Geometry/Soldermask Top")
		(3 "B.Mask" user "Board Geometry/Soldermask Bottom")
		(17 "Dwgs.User" user "User.Drawings")
		(19 "Cmts.User" user "User.Comments")
		(21 "Eco1.User" user "User.Eco1")
		(23 "Eco2.User" user "User.Eco2")
		(25 "Edge.Cuts" user "Board Geometry/Outline")
		(27 "Margin" user)
		(31 "F.CrtYd" user "Package Geometry/Place Bound Top")
		(29 "B.CrtYd" user "Package Geometry/Place Bound Bottom")
		(35 "F.Fab" user "Ref Des/Assembly Top")
		(33 "B.Fab" user "Ref Des/Assembly Bottom")
	)
	(footprint ""
		(layer "F.Cu")
		(at 150.79218 -108.38688 -90)
		(property "Reference" "C576"
			(at 0 0 270)
			(layer "F.SilkS")
			(hide yes)
			(effects
				(font
					(size 1.27 1.27)
				)
			)
		)
		(property "Value" "SCD1U16V2KX-3GP"
			(at 1.1811 -2.7051 270)
			(unlocked yes)
			(layer "F.Fab")
			(hide yes)
			(effects
				(font
					(size 1.016 1.016)
					(thickness 0.1524)
				)
			)
		)
		(property "Device Type" "C402H22"
			(at 1.1811 -4.2291 270)
			(unlocked yes)
			(layer "F.Fab")
			(hide yes)
			(effects
				(font
					(size 1.016 1.016)
					(thickness 0.1524)
				)
			)
		)
		(duplicate_pad_numbers_are_jumpers no)
		(fp_rect
			(start -0.4318 0.9525)
			(end 0.4318 -0.9525)
			(stroke
				(width 0)
				(type default)
			)
			(fill no)
			(layer "F.CrtYd")
		)
		(fp_rect
			(start -0.4318 0.9525)
			(end 0.4318 -0.9525)
			(stroke
				(width 0)
				(type default)
			)
			(fill no)
			(layer "F.Fab")
		)
		(pad "1" smd custom
			(at 0 -0.4445 270)
			(size 0.1524 0.1524)
			(layers "F.Cu" "F.Mask" "F.Paste")
			(net "SDB_CONN_PWR_2")
			(options
				(clearance outline)
				(anchor circle)
			)
			(primitives
				(gr_poly
					(pts
						(arc
							(start 0.3048 -0.2032)
							(mid 0.275042 -0.275042)
							(end 0.2032 -0.3048)
						)
						(arc
							(start -0.2032 -0.3048)
							(mid -0.275042 -0.275042)
							(end -0.3048 -0.2032)
						)
						(arc
							(start -0.3048 0.2032)
							(mid -0.275042 0.275042)
							(end -0.2032 0.3048)
						)
						(arc
							(start 0.2032 0.3048)
							(mid 0.275042 0.275042)
							(end 0.3048 0.2032)
						)
					)
					(width 0)
					(fill yes)
				)
			)
		)
		(pad "2" smd custom
			(at 0 0.4445 270)
			(size 0.1524 0.1524)
			(layers "F.Cu" "F.Mask" "F.Paste")
			(net "GND")
			(options
				(clearance outline)
				(anchor circle)
			)
			(primitives
				(gr_poly
					(pts
						(arc
							(start 0.3048 -0.2032)
							(mid 0.275042 -0.275042)
							(end 0.2032 -0.3048)
						)
						(arc
							(start -0.2032 -0.3048)
							(mid -0.275042 -0.275042)
							(end -0.3048 -0.2032)
						)
						(arc
							(start -0.3048 0.2032)
							(mid -0.275042 0.275042)
							(end -0.2032 0.3048)
						)
						(arc
							(start 0.2032 0.3048)
							(mid 0.275042 0.275042)
							(end 0.3048 0.2032)
						)
					)
					(width 0)
					(fill yes)
				)
			)
		)
	)
	(footprint ""
		(layer "F.Cu")
		(at 70.223126 -94.84995 -90)
		(property "Reference" "R505"
			(at 0 0 270)
			(layer "F.SilkS")
			(hide yes)
			(effects
				(font
					(size 1.27 1.27)
				)
			)
		)
		(property "Value" "100KR2F-L1-GP"
			(at 0.064008 -3.993896 270)
			(unlocked yes)
			(layer "F.Fab")
			(hide yes)
			(effects
				(font
					(size 1.016 1.016)
					(thickness 0.1524)
				)
			)
		)
		(property "Device Type" "R402H16"
			(at 0.064008 -5.517896 270)
			(unlocked yes)
			(layer "F.Fab")
			(hide yes)
			(effects
				(font
					(size 1.016 1.016)
					(thickness 0.1524)
				)
			)
		)
		(duplicate_pad_numbers_are_jumpers no)
		(fp_line
			(start -0.508 -0.9398)
			(end -0.508 0.9398)
			(stroke
				(width 0.1524)
				(type default)
			)
			(layer "F.SilkS")
		)
		(fp_line
			(start 0.508 -0.9398)
			(end -0.508 -0.9398)
			(stroke
				(width 0.1524)
				(type default)
			)
			(layer "F.SilkS")
		)
		(fp_rect
			(start -0.508 0.9398)
			(end 0.508 -0.9398)
			(stroke
				(width 0)
				(type default)
			)
			(fill no)
			(layer "F.CrtYd")
		)
		(fp_rect
			(start -0.508 0.9398)
			(end 0.508 -0.9398)
			(stroke
				(width 0)
				(type default)
			)
			(fill no)
			(layer "F.Fab")
		)
		(pad "1" smd custom
			(at 0 -0.4445 270)
			(size 0.1397 0.1397)
			(layers "F.Cu" "F.Mask" "F.Paste")
			(net "AGND_P3V3")
			(options
				(clearance outline)
				(anchor circle)
			)
			(primitives
				(gr_poly
					(pts
						(arc
							(start -0.1778 -0.2794)
							(mid -0.249642 -0.249642)
							(end -0.2794 -0.1778)
						)
						(arc
							(start -0.2794 0.1778)
							(mid -0.249642 0.249642)
							(end -0.1778 0.2794)
						)
						(arc
							(start 0.1778 0.2794)
							(mid 0.249642 0.249642)
							(end 0.2794 0.1778)
						)
						(arc
							(start 0.2794 -0.1778)
							(mid 0.249642 -0.249642)
							(end 0.1778 -0.2794)
						)
					)
					(width 0)
					(fill yes)
				)
			)
		)
		(pad "2" smd custom
			(at 0 0.4445 270)
			(size 0.1397 0.1397)
			(layers "F.Cu" "F.Mask" "F.Paste")
			(net "P3V3_MODE")
			(options
				(clearance outline)
				(anchor circle)
			)
			(primitives
				(gr_poly
					(pts
						(arc
							(start -0.1778 -0.2794)
							(mid -0.249642 -0.249642)
							(end -0.2794 -0.1778)
						)
						(arc
							(start -0.2794 0.1778)
							(mid -0.249642 0.249642)
							(end -0.1778 0.2794)
						)
						(arc
							(start 0.1778 0.2794)
							(mid 0.249642 0.249642)
							(end 0.2794 0.1778)
						)
						(arc
							(start 0.2794 -0.1778)
							(mid 0.249642 -0.249642)
							(end 0.1778 -0.2794)
						)
					)
					(width 0)
					(fill yes)
				)
			)
		)
	)
	(footprint ""
		(layer "F.Cu")
		(at 57.4548 -103.2256)
		(property "Reference" "C711"
			(at 0 0 0)
			(layer "F.SilkS")
			(hide yes)
			(effects
				(font
					(size 1.27 1.27)
				)
			)
		)
		(property "Value" "SC2200P50V2KX-2GP"
			(at 1.1811 -2.7051 0)
			(unlocked yes)
			(layer "F.Fab")
			(hide yes)
			(effects
				(font
					(size 1.016 1.016)
					(thickness 0.1524)
				)
			)
		)
		(property "Device Type" "C402H22"
			(at 1.1811 -4.2291 0)
			(unlocked yes)
			(layer "F.Fab")
			(hide yes)
			(effects
				(font
					(size 1.016 1.016)
					(thickness 0.1524)
				)
			)
		)
		(duplicate_pad_numbers_are_jumpers no)
		(fp_rect
			(start -0.4318 0.9525)
			(end 0.4318 -0.9525)
			(stroke
				(width 0)
				(type default)
			)
			(fill no)
			(layer "F.CrtYd")
		)
		(fp_rect
			(start -0.4318 0.9525)
			(end 0.4318 -0.9525)
			(stroke
				(width 0)
				(type default)
			)
			(fill no)
			(layer "F.Fab")
		)
		(pad "1" smd custom
			(at 0 -0.4445)
			(size 0.1524 0.1524)
			(layers "F.Cu" "F.Mask" "F.Paste")
			(net "P3V3_LL")
			(options
				(clearance outline)
				(anchor circle)
			)
			(primitives
				(gr_poly
					(pts
						(arc
							(start 0.3048 -0.2032)
							(mid 0.275042 -0.275042)
							(end 0.2032 -0.3048)
						)
						(arc
							(start -0.2032 -0.3048)
							(mid -0.275042 -0.275042)
							(end -0.3048 -0.2032)
						)
						(arc
							(start -0.3048 0.2032)
							(mid -0.275042 0.275042)
							(end -0.2032 0.3048)
						)
						(arc
							(start 0.2032 0.3048)
							(mid 0.275042 0.275042)
							(end 0.3048 0.2032)
						)
					)
					(width 0)
					(fill yes)
				)
			)
		)
		(pad "2" smd custom
			(at 0 0.4445)
			(size 0.1524 0.1524)
			(layers "F.Cu" "F.Mask" "F.Paste")
			(net "P3V3_SNB")
			(options
				(clearance outline)
				(anchor circle)
			)
			(primitives
				(gr_poly
					(pts
						(arc
							(start 0.3048 -0.2032)
							(mid 0.275042 -0.275042)
							(end 0.2032 -0.3048)
						)
						(arc
							(start -0.2032 -0.3048)
							(mid -0.275042 -0.275042)
							(end -0.3048 -0.2032)
						)
						(arc
							(start -0.3048 0.2032)
							(mid -0.275042 0.275042)
							(end -0.2032 0.3048)
						)
						(arc
							(start 0.2032 0.3048)
							(mid 0.275042 0.275042)
							(end 0.3048 0.2032)
						)
					)
					(width 0)
					(fill yes)
				)
			)
		)
	)
	(footprint ""
		(layer "F.Cu")
		(at 136.227312 -79.730092 90)
		(property "Reference" "C679"
			(at 0 0 90)
			(layer "F.SilkS")
			(hide yes)
			(effects
				(font
					(size 1.27 1.27)
				)
			)
		)
		(property "Value" "SCD01U16V1KX-GP"
			(at -2.8321 -1.7399 90)
			(unlocked yes)
			(layer "F.Fab")
			(hide yes)
			(effects
				(font
					(size 1.016 1.016)
					(thickness 0.1524)
				)
			)
		)
		(property "Device Type" "C0201H13"
			(at -2.8321 -3.2639 90)
			(unlocked yes)
			(layer "F.Fab")
			(hide yes)
			(effects
				(font
					(size 1.016 1.016)
					(thickness 0.1524)
				)
			)
		)
		(duplicate_pad_numbers_are_jumpers no)
		(fp_rect
			(start -0.2794 0.6477)
			(end 0.2794 -0.6477)
			(stroke
				(width 0)
				(type default)
			)
			(fill no)
			(layer "F.CrtYd")
		)
		(fp_rect
			(start -0.2794 0.6477)
			(end 0.2794 -0.6477)
			(stroke
				(width 0)
				(type default)
			)
			(fill no)
			(layer "F.Fab")
		)
		(pad "1" smd custom
			(at 0 -0.2794 90)
			(size 0.0762 0.0762)
			(layers "F.Cu" "F.Mask" "F.Paste")
			(net "PHY_EXP_TO_CONN_C_10_DN")
			(options
				(clearance outline)
				(anchor circle)
			)
			(primitives
				(gr_poly
					(pts
						(arc
							(start 0.1524 -0.127)
							(mid 0.137521 -0.162921)
							(end 0.1016 -0.1778)
						)
						(arc
							(start -0.1016 -0.1778)
							(mid -0.137521 -0.162921)
							(end -0.1524 -0.127)
						)
						(arc
							(start -0.1524 0.127)
							(mid -0.137521 0.162921)
							(end -0.1016 0.1778)
						)
						(arc
							(start 0.1016 0.1778)
							(mid 0.137521 0.162921)
							(end 0.1524 0.127)
						)
					)
					(width 0)
					(fill yes)
				)
			)
		)
		(pad "2" smd custom
			(at 0 0.2794 90)
			(size 0.0762 0.0762)
			(layers "F.Cu" "F.Mask" "F.Paste")
			(net "PHY_EXP_TO_CONN_10_DN")
			(options
				(clearance outline)
				(anchor circle)
			)
			(primitives
				(gr_poly
					(pts
						(arc
							(start 0.1524 -0.127)
							(mid 0.137521 -0.162921)
							(end 0.1016 -0.1778)
						)
						(arc
							(start -0.1016 -0.1778)
							(mid -0.137521 -0.162921)
							(end -0.1524 -0.127)
						)
						(arc
							(start -0.1524 0.127)
							(mid -0.137521 0.162921)
							(end -0.1016 0.1778)
						)
						(arc
							(start 0.1016 0.1778)
							(mid 0.137521 0.162921)
							(end 0.1524 0.127)
						)
					)
					(width 0)
					(fill yes)
				)
			)
		)
	)
	(footprint ""
		(layer "F.Cu")
		(at 139.60221 -61.122052)
		(property "Reference" "VIA14"
			(at 0 0 0)
			(layer "F.SilkS")
			(hide yes)
			(effects
				(font
					(size 1.27 1.27)
				)
			)
		)
		(property "Value" "100OHM-8L-1D6MM-L13-GP"
			(at 3.2893 0.0508 0)
			(unlocked yes)
			(layer "F.Fab")
			(hide yes)
			(effects
				(font
					(size 1.016 1.016)
					(thickness 0.1524)
				)
			)
		)
		(property "Device Type" "VIA-PCIE-4P-409091"
			(at 3.2893 -1.4732 0)
			(unlocked yes)
			(layer "F.Fab")
			(hide yes)
			(effects
				(font
					(size 1.016 1.016)
					(thickness 0.1524)
				)
			)
		)
		(duplicate_pad_numbers_are_jumpers no)
		(fp_rect
			(start -2.0447 0.4572)
			(end 2.0447 -0.4572)
			(stroke
				(width 0)
				(type default)
			)
			(fill no)
			(layer "F.CrtYd")
		)
		(fp_rect
			(start -2.0447 0.4572)
			(end 2.0447 -0.4572)
			(stroke
				(width 0)
				(type default)
			)
			(fill no)
			(layer "F.Fab")
		)
		(pad "1" thru_hole circle
			(at -1.5875 0)
			(size 0.508 0.508)
			(drill 0.254)
			(layers "*.Cu" "*.Mask")
			(remove_unused_layers no)
			(net "GND")
			(clearance 0.2032)
			(thermal_gap 0.2032)
		)
		(pad "2" thru_hole circle
			(at -0.5715 0)
			(size 0.508 0.508)
			(drill 0.254)
			(layers "*.Cu" "*.Mask")
			(remove_unused_layers no)
			(net "PHY_IOC_TO_SCC_C_45_DP")
			(clearance 0.2032)
			(thermal_gap 0.2032)
		)
		(pad "3" thru_hole circle
			(at 0.5715 0)
			(size 0.508 0.508)
			(drill 0.254)
			(layers "*.Cu" "*.Mask")
			(remove_unused_layers no)
			(net "PHY_IOC_TO_SCC_C_45_DN")
			(clearance 0.2032)
			(thermal_gap 0.2032)
		)
		(pad "4" thru_hole circle
			(at 1.5875 0)
			(size 0.508 0.508)
			(drill 0.254)
			(layers "*.Cu" "*.Mask")
			(remove_unused_layers no)
			(net "GND")
			(clearance 0.2032)
			(thermal_gap 0.2032)
		)
	)
	(footprint ""
		(layer "F.Cu")
		(at 6.1849 -93.358208 90)
		(property "Reference" "R415"
			(at 0 0 90)
			(layer "F.SilkS")
			(hide yes)
			(effects
				(font
					(size 1.27 1.27)
				)
			)
		)
		(property "Value" "0R2J-2-GP"
			(at 0.064008 -3.993896 90)
			(unlocked yes)
			(layer "F.Fab")
			(hide yes)
			(effects
				(font
					(size 1.016 1.016)
					(thickness 0.1524)
				)
			)
		)
		(property "Device Type" "R402H16"
			(at 0.064008 -5.517896 90)
			(unlocked yes)
			(layer "F.Fab")
			(hide yes)
			(effects
				(font
					(size 1.016 1.016)
					(thickness 0.1524)
				)
			)
		)
		(duplicate_pad_numbers_are_jumpers no)
		(fp_line
			(start 0.508 -0.9398)
			(end -0.508 -0.9398)
			(stroke
				(width 0.1524)
				(type default)
			)
			(layer "F.SilkS")
		)
		(fp_line
			(start -0.508 -0.9398)
			(end -0.508 0.9398)
			(stroke
				(width 0.1524)
				(type default)
			)
			(layer "F.SilkS")
		)
		(fp_rect
			(start -0.508 0.9398)
			(end 0.508 -0.9398)
			(stroke
				(width 0)
				(type default)
			)
			(fill no)
			(layer "F.CrtYd")
		)
		(fp_rect
			(start -0.508 0.9398)
			(end 0.508 -0.9398)
			(stroke
				(width 0)
				(type default)
			)
			(fill no)
			(layer "F.Fab")
		)
		(pad "1" smd custom
			(at 0 -0.4445 90)
			(size 0.1397 0.1397)
			(layers "F.Cu" "F.Mask" "F.Paste")
			(net "LS_EN_U36")
			(options
				(clearance outline)
				(anchor circle)
			)
			(primitives
				(gr_poly
					(pts
						(arc
							(start -0.1778 -0.2794)
							(mid -0.249642 -0.249642)
							(end -0.2794 -0.1778)
						)
						(arc
							(start -0.2794 0.1778)
							(mid -0.249642 0.249642)
							(end -0.1778 0.2794)
						)
						(arc
							(start 0.1778 0.2794)
							(mid 0.249642 0.249642)
							(end 0.2794 0.1778)
						)
						(arc
							(start 0.2794 -0.1778)
							(mid 0.249642 -0.249642)
							(end 0.1778 -0.2794)
						)
					)
					(width 0)
					(fill yes)
				)
			)
		)
		(pad "2" smd custom
			(at 0 0.4445 90)
			(size 0.1397 0.1397)
			(layers "F.Cu" "F.Mask" "F.Paste")
			(net "VREF2")
			(options
				(clearance outline)
				(anchor circle)
			)
			(primitives
				(gr_poly
					(pts
						(arc
							(start -0.1778 -0.2794)
							(mid -0.249642 -0.249642)
							(end -0.2794 -0.1778)
						)
						(arc
							(start -0.2794 0.1778)
							(mid -0.249642 0.249642)
							(end -0.1778 0.2794)
						)
						(arc
							(start 0.1778 0.2794)
							(mid 0.249642 0.249642)
							(end 0.2794 0.1778)
						)
						(arc
							(start 0.2794 -0.1778)
							(mid 0.249642 -0.249642)
							(end 0.1778 -0.2794)
						)
					)
					(width 0)
					(fill yes)
				)
			)
		)
	)
	(footprint ""
		(layer "F.Cu")
		(at 21.7932 -55.3466 90)
		(property "Reference" "R20"
			(at 0 0 90)
			(layer "F.SilkS")
			(hide yes)
			(effects
				(font
					(size 1.27 1.27)
				)
			)
		)
		(property "Value" "63K4R2B-GP"
			(at 0.064008 -3.993896 90)
			(unlocked yes)
			(layer "F.Fab")
			(hide yes)
			(effects
				(font
					(size 1.016 1.016)
					(thickness 0.1524)
				)
			)
		)
		(property "Device Type" "R402H16"
			(at 0.064008 -5.517896 90)
			(unlocked yes)
			(layer "F.Fab")
			(hide yes)
			(effects
				(font
					(size 1.016 1.016)
					(thickness 0.1524)
				)
			)
		)
		(duplicate_pad_numbers_are_jumpers no)
		(fp_line
			(start 0.508 -0.9398)
			(end -0.508 -0.9398)
			(stroke
				(width 0.1524)
				(type default)
			)
			(layer "F.SilkS")
		)
		(fp_line
			(start -0.508 -0.9398)
			(end -0.508 0.9398)
			(stroke
				(width 0.1524)
				(type default)
			)
			(layer "F.SilkS")
		)
		(fp_rect
			(start -0.508 0.9398)
			(end 0.508 -0.9398)
			(stroke
				(width 0)
				(type default)
			)
			(fill no)
			(layer "F.CrtYd")
		)
		(fp_rect
			(start -0.508 0.9398)
			(end 0.508 -0.9398)
			(stroke
				(width 0)
				(type default)
			)
			(fill no)
			(layer "F.Fab")
		)
		(pad "1" smd custom
			(at 0 -0.4445 90)
			(size 0.1397 0.1397)
			(layers "F.Cu" "F.Mask" "F.Paste")
			(net "MB0_ISET_R")
			(options
				(clearance outline)
				(anchor circle)
			)
			(primitives
				(gr_poly
					(pts
						(arc
							(start -0.1778 -0.2794)
							(mid -0.249642 -0.249642)
							(end -0.2794 -0.1778)
						)
						(arc
							(start -0.2794 0.1778)
							(mid -0.249642 0.249642)
							(end -0.1778 0.2794)
						)
						(arc
							(start 0.1778 0.2794)
							(mid 0.249642 0.249642)
							(end 0.2794 0.1778)
						)
						(arc
							(start 0.2794 -0.1778)
							(mid 0.249642 -0.249642)
							(end 0.1778 -0.2794)
						)
					)
					(width 0)
					(fill yes)
				)
			)
		)
		(pad "2" smd custom
			(at 0 0.4445 90)
			(size 0.1397 0.1397)
			(layers "F.Cu" "F.Mask" "F.Paste")
			(net "AGND_CURRENT_MON")
			(options
				(clearance outline)
				(anchor circle)
			)
			(primitives
				(gr_poly
					(pts
						(arc
							(start -0.1778 -0.2794)
							(mid -0.249642 -0.249642)
							(end -0.2794 -0.1778)
						)
						(arc
							(start -0.2794 0.1778)
							(mid -0.249642 0.249642)
							(end -0.1778 0.2794)
						)
						(arc
							(start 0.1778 0.2794)
							(mid 0.249642 0.249642)
							(end 0.2794 0.1778)
						)
						(arc
							(start 0.2794 -0.1778)
							(mid 0.249642 -0.249642)
							(end 0.1778 -0.2794)
						)
					)
					(width 0)
					(fill yes)
				)
			)
		)
	)
	(footprint ""
		(layer "F.Cu")
		(at 17.6022 -94.9452 180)
		(property "Reference" "C542"
			(at 0 0 180)
			(layer "F.SilkS")
			(hide yes)
			(effects
				(font
					(size 1.27 1.27)
				)
			)
		)
		(property "Value" "SCD1U16V2KX-3GP"
			(at 1.1811 -2.7051 180)
			(unlocked yes)
			(layer "F.Fab")
			(hide yes)
			(effects
				(font
					(size 1.016 1.016)
					(thickness 0.1524)
				)
			)
		)
		(property "Device Type" "C402H22"
			(at 1.1811 -4.2291 180)
			(unlocked yes)
			(layer "F.Fab")
			(hide yes)
			(effects
				(font
					(size 1.016 1.016)
					(thickness 0.1524)
				)
			)
		)
		(duplicate_pad_numbers_are_jumpers no)
		(fp_rect
			(start -0.4318 0.9525)
			(end 0.4318 -0.9525)
			(stroke
				(width 0)
				(type default)
			)
			(fill no)
			(layer "F.CrtYd")
		)
		(fp_rect
			(start -0.4318 0.9525)
			(end 0.4318 -0.9525)
			(stroke
				(width 0)
				(type default)
			)
			(fill no)
			(layer "F.Fab")
		)
		(pad "1" smd custom
			(at 0 -0.4445 180)
			(size 0.1524 0.1524)
			(layers "F.Cu" "F.Mask" "F.Paste")
			(net "VREF0")
			(options
				(clearance outline)
				(anchor circle)
			)
			(primitives
				(gr_poly
					(pts
						(arc
							(start 0.3048 -0.2032)
							(mid 0.275042 -0.275042)
							(end 0.2032 -0.3048)
						)
						(arc
							(start -0.2032 -0.3048)
							(mid -0.275042 -0.275042)
							(end -0.3048 -0.2032)
						)
						(arc
							(start -0.3048 0.2032)
							(mid -0.275042 0.275042)
							(end -0.2032 0.3048)
						)
						(arc
							(start 0.2032 0.3048)
							(mid 0.275042 0.275042)
							(end 0.3048 0.2032)
						)
					)
					(width 0)
					(fill yes)
				)
			)
		)
		(pad "2" smd custom
			(at 0 0.4445 180)
			(size 0.1524 0.1524)
			(layers "F.Cu" "F.Mask" "F.Paste")
			(net "GND")
			(options
				(clearance outline)
				(anchor circle)
			)
			(primitives
				(gr_poly
					(pts
						(arc
							(start 0.3048 -0.2032)
							(mid 0.275042 -0.275042)
							(end 0.2032 -0.3048)
						)
						(arc
							(start -0.2032 -0.3048)
							(mid -0.275042 -0.275042)
							(end -0.3048 -0.2032)
						)
						(arc
							(start -0.3048 0.2032)
							(mid -0.275042 0.275042)
							(end -0.2032 0.3048)
						)
						(arc
							(start 0.2032 0.3048)
							(mid 0.275042 0.275042)
							(end 0.3048 0.2032)
						)
					)
					(width 0)
					(fill yes)
				)
			)
		)
	)
)
